# TIMECARD (Time Appliance Project (Time Card)) — schematic netlist excerpt (pin names and nets, part order shuffled) for the footprints in the layout excerpt that follows; sources: Cadence DE-HDL packaged netlist, KiCad conversion of R4006-B0001-02_R01.brd

C192  CAPACITOR  0.01UF 25V 10%  pkg SMC_0201R  page 30 : \1\ = XP1R2V_PG_R ; \2\ = SG

(kicad_pcb
	(version 20260206)
	(generator "pcbnew")
	(generator_version "10.0")
	(general
		(thickness 1.6)
		(legacy_teardrops no)
	)
	(paper "A4")
	(title_block
		(title "timecard-production-celestica-r4006 — R4006-B0001-02_R01.brd")
		(comment 1 "Time Appliance Project (Time Card) / footprints 252-252 of 1113")
	)
	(layers
		(0 "F.Cu" signal "TOP")
		(4 "In1.Cu" signal "L02_GND1")
		(6 "In2.Cu" signal "L03_SIG1")
		(8 "In3.Cu" signal "L04_GND2")
		(10 "In4.Cu" signal "L05_VCC1")
		(12 "In5.Cu" signal "L06_VCC2")
		(14 "In6.Cu" signal "L07_GND3")
		(16 "In7.Cu" signal "L08_SIG2")
		(18 "In8.Cu" signal "L09_GND4")
		(2 "B.Cu" signal "BOTTOM")
		(9 "F.Adhes" user "F.Adhesive")
		(11 "B.Adhes" user "B.Adhesive")
		(13 "F.Paste" user "Package Geometry/Pastemask Top")
		(15 "B.Paste" user "Package Geometry/Pastemask Bottom")
		(5 "F.SilkS" user "Ref Des/Silkscreen Top")
		(7 "B.SilkS" user "Ref Des/Silkscreen Bottom")
		(1 "F.Mask" user "Board Geometry/Soldermask Top")
		(3 "B.Mask" user "Board Geometry/Soldermask Bottom")
		(17 "Dwgs.User" user "User.Drawings")
		(19 "Cmts.User" user "User.Comments")
		(21 "Eco1.User" user "User.Eco1")
		(23 "Eco2.User" user "User.Eco2")
		(25 "Edge.Cuts" user "Board Geometry/Outline")
		(27 "Margin" user)
		(31 "F.CrtYd" user "Package Geometry/Place Bound Top")
		(29 "B.CrtYd" user "Package Geometry/Place Bound Bottom")
		(35 "F.Fab" user "Ref Des/Assembly Top")
		(33 "B.Fab" user "Ref Des/Assembly Bottom")
	)
	(footprint ""
		(layer "F.Cu")
		(at 100.3808 -70.4596)
		(property "Reference" "C192"
			(at 2.7432 0.14097 0)
			(unlocked yes)
			(layer "F.SilkS")
			(effects
				(font
					(size 0.7874 0.5842)
					(thickness 0.1524)
				)
			)
		)
		(property "Value" "VAL*"
			(at 0.193548 2.13614 0)
			(unlocked yes)
			(layer "F.Fab")
			(hide yes)
			(effects
				(font
					(size 0.7874 0.5842)
					(thickness 0.1524)
				)
			)
		)
		(property "User Part Number" "PARTNUM*"
			(at 0.216154 4.185666 0)
			(unlocked yes)
			(layer "Cmts.User")
			(hide yes)
			(effects
				(font
					(size 0.7874 0.5842)
					(thickness 0.1524)
				)
			)
		)
		(property "Device Type" "CAPACITOR-G104-0B103-EK,0.01UFA"
			(at 0.184404 1.180592 0)
			(unlocked yes)
			(layer "F.Fab")
			(hide yes)
			(effects
				(font
					(size 0.7874 0.5842)
					(thickness 0.1524)
				)
			)
		)
		(property "Tolerance" "TOL*"
			(at 0.216154 3.1496 0)
			(unlocked yes)
			(layer "Cmts.User")
			(hide yes)
			(effects
				(font
					(size 0.7874 0.5842)
					(thickness 0.1524)
				)
			)
		)
		(duplicate_pad_numbers_are_jumpers no)
		(fp_line
			(start -0.671322 -0.4445)
			(end 0.671322 -0.4445)
			(stroke
				(width 0.1)
				(type default)
			)
			(layer "F.SilkS")
		)
		(fp_line
			(start -0.671322 0.4445)
			(end -0.671322 -0.4445)
			(stroke
				(width 0.1)
				(type default)
			)
			(layer "F.SilkS")
		)
		(fp_line
			(start 0.671322 -0.4445)
			(end 0.671322 0.4445)
			(stroke
				(width 0.1)
				(type default)
			)
			(layer "F.SilkS")
		)
		(fp_line
			(start 0.671322 0.4445)
			(end -0.671322 0.4445)
			(stroke
				(width 0.1)
				(type default)
			)
			(layer "F.SilkS")
		)
		(fp_rect
			(start -0.671322 -0.4445)
			(end 0.671322 0.4445)
			(stroke
				(width 0)
				(type default)
			)
			(fill no)
			(layer "F.CrtYd")
		)
		(fp_line
			(start -0.31496 -0.1651)
			(end -0.31496 0.1651)
			(stroke
				(width 0.1)
				(type default)
			)
			(layer "F.Fab")
		)
		(fp_line
			(start -0.31496 0.1651)
			(end 0.31496 0.1651)
			(stroke
				(width 0.1)
				(type default)
			)
			(layer "F.Fab")
		)
		(fp_line
			(start 0.31496 -0.1651)
			(end -0.31496 -0.1651)
			(stroke
				(width 0.1)
				(type default)
			)
			(layer "F.Fab")
		)
		(fp_line
			(start 0.31496 0.1651)
			(end 0.31496 -0.1651)
			(stroke
				(width 0.1)
				(type default)
			)
			(layer "F.Fab")
		)
		(pad "1" smd rect
			(at -0.264922 0)
			(size 0.3048 0.381)
			(layers "F.Cu" "F.Mask" "F.Paste")
			(net "XP1R2V_PG_R")
		)
		(pad "2" smd rect
			(at 0.264922 0)
			(size 0.3048 0.381)
			(layers "F.Cu" "F.Mask" "F.Paste")
			(net "SG")
		)
		(zone
			(layer "F.Cu")
			(hatch none 0.5)
			(connect_pads
				(clearance 0)
			)
			(min_thickness 0.25)
			(keepout
				(tracks allowed)
				(vias not_allowed)
				(pads allowed)
				(copperpour not_allowed)
				(footprints allowed)
			)
			(placement
				(enabled no)
				(sheetname "")
			)
			(fill
				(thermal_gap 0.5)
				(thermal_bridge_width 0.5)
				(island_removal_mode 0)
			)
			(polygon
				(pts
					(xy 100.268278 -70.6501) (xy 100.268278 -70.2691) (xy 100.493322 -70.2691) (xy 100.493322 -70.6501)
				)
			)
		)
	)
)
